(kicad_pcb
	(version 20260206)
	(generator "pcbnew")
	(generator_version "10.0")
	(general
		(thickness 1.6)
		(legacy_teardrops no)
	)
	(paper "A4")
	(title_block
		(title "9052_F0T_PDB_Converter_Brick_F_V03_1208_1600_OCP.brd")
		(comment 1 "Grand Teton / footprints 232-238 of 578")
	)
	(layers
		(0 "F.Cu" signal "TOP")
		(4 "In1.Cu" signal "GND")
		(6 "In2.Cu" signal "IN1")
		(8 "In3.Cu" signal "GND1")
		(10 "In4.Cu" signal "VCC")
		(12 "In5.Cu" signal "VCC1")
		(14 "In6.Cu" signal "GND2")
		(16 "In7.Cu" signal "IN2")
		(18 "In8.Cu" signal "GND3")
		(2 "B.Cu" signal "BOTTOM")
		(9 "F.Adhes" user "F.Adhesive")
		(11 "B.Adhes" user "B.Adhesive")
		(13 "F.Paste" user "Package Geometry/Pastemask Top")
		(15 "B.Paste" user "Package Geometry/Pastemask Bottom")
		(5 "F.SilkS" user "Ref Des/Silkscreen Top")
		(7 "B.SilkS" user "Ref Des/Silkscreen Bottom")
		(1 "F.Mask" user "Board Geometry/Soldermask Top")
		(3 "B.Mask" user "Board Geometry/Soldermask Bottom")
		(17 "Dwgs.User" user "User.Drawings")
		(19 "Cmts.User" user "User.Comments")
		(21 "Eco1.User" user "User.Eco1")
		(23 "Eco2.User" user "User.Eco2")
		(25 "Edge.Cuts" user "Board Geometry/Outline")
		(27 "Margin" user)
		(31 "F.CrtYd" user "Package Geometry/Place Bound Top")
		(29 "B.CrtYd" user "Package Geometry/Place Bound Bottom")
		(35 "F.Fab" user "Ref Des/Assembly Top")
		(33 "B.Fab" user "Ref Des/Assembly Bottom")
	)
	(footprint ""
		(layer "F.Cu")
		(at 174.879 -8.255 180)
		(property "Reference" "R83"
			(at 0 0 180)
			(layer "F.SilkS")
			(hide yes)
			(effects
				(font
					(size 1.27 1.27)
				)
			)
		)
		(property "Value" ""
			(at 0 0 180)
			(layer "F.Fab")
			(effects
				(font
					(size 1.27 1.27)
				)
			)
		)
		(duplicate_pad_numbers_are_jumpers no)
		(fp_line
			(start 0.7874 0.4064)
			(end -0.7874 0.4064)
			(stroke
				(width 0.1524)
				(type default)
			)
			(layer "F.SilkS")
		)
		(fp_line
			(start 0.7874 -0.4064)
			(end 0.7874 0.4064)
			(stroke
				(width 0.1524)
				(type default)
			)
			(layer "F.SilkS")
		)
		(fp_line
			(start -0.7874 0.4064)
			(end -0.7874 -0.4064)
			(stroke
				(width 0.1524)
				(type default)
			)
			(layer "F.SilkS")
		)
		(fp_line
			(start -0.7874 -0.4064)
			(end 0.7874 -0.4064)
			(stroke
				(width 0.1524)
				(type default)
			)
			(layer "F.SilkS")
		)
		(fp_line
			(start 0.67945 0.3048)
			(end 0.120396 0.3048)
			(stroke
				(width 0.1)
				(type default)
			)
			(layer "F.Fab")
		)
		(fp_line
			(start 0.67945 -0.3048)
			(end 0.67945 0.3048)
			(stroke
				(width 0.1)
				(type default)
			)
			(layer "F.Fab")
		)
		(fp_line
			(start 0.12065 -0.2794)
			(end 0.12065 -0.3048)
			(stroke
				(width 0.1)
				(type default)
			)
			(layer "F.Fab")
		)
		(fp_line
			(start 0.12065 -0.3048)
			(end 0.67945 -0.3048)
			(stroke
				(width 0.1)
				(type default)
			)
			(layer "F.Fab")
		)
		(fp_line
			(start 0.120396 0.3048)
			(end 0.120396 0.2794)
			(stroke
				(width 0.1)
				(type default)
			)
			(layer "F.Fab")
		)
		(fp_line
			(start 0.120396 0.2794)
			(end -0.12065 0.2794)
			(stroke
				(width 0.1)
				(type default)
			)
			(layer "F.Fab")
		)
		(fp_line
			(start -0.12065 0.3048)
			(end -0.67945 0.3048)
			(stroke
				(width 0.1)
				(type default)
			)
			(layer "F.Fab")
		)
		(fp_line
			(start -0.12065 0.2794)
			(end -0.12065 0.3048)
			(stroke
				(width 0.1)
				(type default)
			)
			(layer "F.Fab")
		)
		(fp_line
			(start -0.12065 -0.2794)
			(end 0.12065 -0.2794)
			(stroke
				(width 0.1)
				(type default)
			)
			(layer "F.Fab")
		)
		(fp_line
			(start -0.12065 -0.305054)
			(end -0.12065 -0.2794)
			(stroke
				(width 0.1)
				(type default)
			)
			(layer "F.Fab")
		)
		(fp_line
			(start -0.67945 0.3048)
			(end -0.67945 -0.305054)
			(stroke
				(width 0.1)
				(type default)
			)
			(layer "F.Fab")
		)
		(fp_line
			(start -0.67945 -0.305054)
			(end -0.12065 -0.305054)
			(stroke
				(width 0.1)
				(type default)
			)
			(layer "F.Fab")
		)
		(pad "1" smd circle
			(at -0.40005 0 180)
			(size 0 0)
			(layers "F.Cu" "F.Mask" "F.Paste")
			(net "P12V_BRICK0_PWRGD")
		)
		(pad "2" smd circle
			(at 0.40005 0 180)
			(size 0 0)
			(layers "F.Cu" "F.Mask" "F.Paste")
			(net "GND")
		)
	)
	(footprint ""
		(layer "F.Cu")
		(at 46.042834 -53.613304 90)
		(property "Reference" "C91"
			(at 0 0 90)
			(layer "F.SilkS")
			(hide yes)
			(effects
				(font
					(size 1.27 1.27)
				)
			)
		)
		(property "Value" ""
			(at 0 0 90)
			(layer "F.Fab")
			(effects
				(font
					(size 1.27 1.27)
				)
			)
		)
		(duplicate_pad_numbers_are_jumpers no)
		(fp_line
			(start 0.7874 -0.4064)
			(end 0.7874 0.4064)
			(stroke
				(width 0.1524)
				(type default)
			)
			(layer "F.SilkS")
		)
		(fp_line
			(start -0.7874 -0.4064)
			(end 0.7874 -0.4064)
			(stroke
				(width 0.1524)
				(type default)
			)
			(layer "F.SilkS")
		)
		(fp_line
			(start 0.7874 0.4064)
			(end -0.7874 0.4064)
			(stroke
				(width 0.1524)
				(type default)
			)
			(layer "F.SilkS")
		)
		(fp_line
			(start -0.7874 0.4064)
			(end -0.7874 -0.4064)
			(stroke
				(width 0.1524)
				(type default)
			)
			(layer "F.SilkS")
		)
		(fp_line
			(start 0.6858 -0.3048)
			(end 0.6858 0.3048)
			(stroke
				(width 0.1)
				(type default)
			)
			(layer "F.Fab")
		)
		(fp_line
			(start 0.1016 -0.3048)
			(end 0.6858 -0.3048)
			(stroke
				(width 0.1)
				(type default)
			)
			(layer "F.Fab")
		)
		(fp_line
			(start -0.1016 -0.3048)
			(end -0.1016 -0.2794)
			(stroke
				(width 0.1)
				(type default)
			)
			(layer "F.Fab")
		)
		(fp_line
			(start -0.6858 -0.3048)
			(end -0.1016 -0.3048)
			(stroke
				(width 0.1)
				(type default)
			)
			(layer "F.Fab")
		)
		(fp_line
			(start 0.1016 -0.2794)
			(end 0.1016 -0.3048)
			(stroke
				(width 0.1)
				(type default)
			)
			(layer "F.Fab")
		)
		(fp_line
			(start -0.1016 -0.2794)
			(end 0.1016 -0.2794)
			(stroke
				(width 0.1)
				(type default)
			)
			(layer "F.Fab")
		)
		(fp_line
			(start 0.1016 0.2794)
			(end -0.1016 0.2794)
			(stroke
				(width 0.1)
				(type default)
			)
			(layer "F.Fab")
		)
		(fp_line
			(start -0.1016 0.2794)
			(end -0.1016 0.3048)
			(stroke
				(width 0.1)
				(type default)
			)
			(layer "F.Fab")
		)
		(fp_line
			(start 0.6858 0.3048)
			(end 0.1016 0.3048)
			(stroke
				(width 0.1)
				(type default)
			)
			(layer "F.Fab")
		)
		(fp_line
			(start 0.1016 0.3048)
			(end 0.1016 0.2794)
			(stroke
				(width 0.1)
				(type default)
			)
			(layer "F.Fab")
		)
		(fp_line
			(start -0.1016 0.3048)
			(end -0.6858 0.3048)
			(stroke
				(width 0.1)
				(type default)
			)
			(layer "F.Fab")
		)
		(fp_line
			(start -0.6858 0.3048)
			(end -0.6858 -0.3048)
			(stroke
				(width 0.1)
				(type default)
			)
			(layer "F.Fab")
		)
		(pad "1" smd rect
			(at -0.40005 0 270)
			(size 0.4572 0.508)
			(layers "F.Cu" "F.Mask" "F.Paste")
			(net "P12V_BRICK")
		)
		(pad "2" smd rect
			(at 0.40005 0 270)
			(size 0.4572 0.508)
			(layers "F.Cu" "F.Mask" "F.Paste")
			(net "GND")
		)
	)
	(footprint ""
		(layer "F.Cu")
		(at 270.383 -129.753868 -90)
		(property "Reference" "PR8"
			(at 0 0 270)
			(layer "F.SilkS")
			(hide yes)
			(effects
				(font
					(size 1.27 1.27)
				)
			)
		)
		(property "Value" ""
			(at 0 0 270)
			(layer "F.Fab")
			(effects
				(font
					(size 1.27 1.27)
				)
			)
		)
		(duplicate_pad_numbers_are_jumpers no)
		(fp_line
			(start -1.2954 0.5842)
			(end -1.2954 -0.5842)
			(stroke
				(width 0.1524)
				(type default)
			)
			(layer "F.SilkS")
		)
		(fp_line
			(start 1.2954 0.5842)
			(end -1.2954 0.5842)
			(stroke
				(width 0.1524)
				(type default)
			)
			(layer "F.SilkS")
		)
		(fp_line
			(start -1.2954 -0.5842)
			(end 1.2954 -0.5842)
			(stroke
				(width 0.1524)
				(type default)
			)
			(layer "F.SilkS")
		)
		(fp_line
			(start 1.2954 -0.5842)
			(end 1.2954 0.5842)
			(stroke
				(width 0.1524)
				(type default)
			)
			(layer "F.SilkS")
		)
		(fp_line
			(start -0.8636 0.4572)
			(end -0.8636 0.4318)
			(stroke
				(width 0.1)
				(type default)
			)
			(layer "F.Fab")
		)
		(fp_line
			(start 0.8636 0.4572)
			(end -0.8636 0.4572)
			(stroke
				(width 0.1)
				(type default)
			)
			(layer "F.Fab")
		)
		(fp_line
			(start -0.8636 0.4318)
			(end -0.8636 0.4064)
			(stroke
				(width 0.1)
				(type default)
			)
			(layer "F.Fab")
		)
		(fp_line
			(start -1.1938 0.4064)
			(end -1.1938 -0.406654)
			(stroke
				(width 0.1)
				(type default)
			)
			(layer "F.Fab")
		)
		(fp_line
			(start -0.8636 0.4064)
			(end -1.1938 0.4064)
			(stroke
				(width 0.1)
				(type default)
			)
			(layer "F.Fab")
		)
		(fp_line
			(start 0.8636 0.4064)
			(end 0.8636 0.4572)
			(stroke
				(width 0.1)
				(type default)
			)
			(layer "F.Fab")
		)
		(fp_line
			(start 1.1938 0.4064)
			(end 0.8636 0.4064)
			(stroke
				(width 0.1)
				(type default)
			)
			(layer "F.Fab")
		)
		(fp_line
			(start -1.1938 -0.406654)
			(end -0.8636 -0.406654)
			(stroke
				(width 0.1)
				(type default)
			)
			(layer "F.Fab")
		)
		(fp_line
			(start -0.8636 -0.406654)
			(end -0.8636 -0.4572)
			(stroke
				(width 0.1)
				(type default)
			)
			(layer "F.Fab")
		)
		(fp_line
			(start 0.8636 -0.406654)
			(end 1.1938 -0.406654)
			(stroke
				(width 0.1)
				(type default)
			)
			(layer "F.Fab")
		)
		(fp_line
			(start 1.1938 -0.406654)
			(end 1.1938 0.4064)
			(stroke
				(width 0.1)
				(type default)
			)
			(layer "F.Fab")
		)
		(fp_line
			(start -0.8636 -0.4572)
			(end 0.8636 -0.4572)
			(stroke
				(width 0.1)
				(type default)
			)
			(layer "F.Fab")
		)
		(fp_line
			(start 0.8636 -0.4572)
			(end 0.8636 -0.406654)
			(stroke
				(width 0.1)
				(type default)
			)
			(layer "F.Fab")
		)
		(pad "1" smd rect
			(at -0.7366 0 180)
			(size 0.7112 0.8128)
			(layers "F.Cu" "F.Mask" "F.Paste")
			(net "P52V_HS1_GATE1_R")
		)
		(pad "2" smd rect
			(at 0.7366 0 180)
			(size 0.7112 0.8128)
			(layers "F.Cu" "F.Mask" "F.Paste")
			(net "P52V_HS1_GATE1")
		)
	)
	(footprint ""
		(layer "F.Cu")
		(at 157.226 -51.816)
		(property "Reference" "PC37"
			(at 0 0 0)
			(layer "F.SilkS")
			(hide yes)
			(effects
				(font
					(size 1.27 1.27)
				)
			)
		)
		(property "Value" ""
			(at 0 0 0)
			(layer "F.Fab")
			(effects
				(font
					(size 1.27 1.27)
				)
			)
		)
		(duplicate_pad_numbers_are_jumpers no)
		(fp_line
			(start -1.524 -0.762)
			(end 1.524 -0.762)
			(stroke
				(width 0.1524)
				(type default)
			)
			(layer "F.SilkS")
		)
		(fp_line
			(start -1.524 0.762)
			(end -1.524 -0.762)
			(stroke
				(width 0.1524)
				(type default)
			)
			(layer "F.SilkS")
		)
		(fp_line
			(start 1.524 -0.762)
			(end 1.524 0.762)
			(stroke
				(width 0.1524)
				(type default)
			)
			(layer "F.SilkS")
		)
		(fp_line
			(start 1.524 0.762)
			(end -1.524 0.762)
			(stroke
				(width 0.1524)
				(type default)
			)
			(layer "F.SilkS")
		)
		(fp_line
			(start -1.1049 -0.724916)
			(end -1.1049 0.724916)
			(stroke
				(width 0.1)
				(type default)
			)
			(layer "F.Fab")
		)
		(fp_line
			(start -1.1049 0.724916)
			(end 1.1049 0.724916)
			(stroke
				(width 0.1)
				(type default)
			)
			(layer "F.Fab")
		)
		(fp_line
			(start 1.1049 -0.724916)
			(end -1.1049 -0.724916)
			(stroke
				(width 0.1)
				(type default)
			)
			(layer "F.Fab")
		)
		(fp_line
			(start 1.1049 0.724916)
			(end 1.1049 -0.724916)
			(stroke
				(width 0.1)
				(type default)
			)
			(layer "F.Fab")
		)
		(pad "1" smd rect
			(at -0.889 0 180)
			(size 1.016 1.27)
			(layers "F.Cu" "F.Mask" "F.Paste")
			(net "P12V_BRICK")
		)
		(pad "2" smd rect
			(at 0.889 0 180)
			(size 1.016 1.27)
			(layers "F.Cu" "F.Mask" "F.Paste")
			(net "GND")
		)
	)
	(footprint ""
		(layer "F.Cu")
		(at 45.67936 -56.09082)
		(property "Reference" "C94"
			(at 0 0 0)
			(layer "F.SilkS")
			(hide yes)
			(effects
				(font
					(size 1.27 1.27)
				)
			)
		)
		(property "Value" ""
			(at 0 0 0)
			(layer "F.Fab")
			(effects
				(font
					(size 1.27 1.27)
				)
			)
		)
		(duplicate_pad_numbers_are_jumpers no)
		(fp_line
			(start -0.7874 -0.4064)
			(end 0.7874 -0.4064)
			(stroke
				(width 0.1524)
				(type default)
			)
			(layer "F.SilkS")
		)
		(fp_line
			(start -0.7874 0.4064)
			(end -0.7874 -0.4064)
			(stroke
				(width 0.1524)
				(type default)
			)
			(layer "F.SilkS")
		)
		(fp_line
			(start 0.7874 -0.4064)
			(end 0.7874 0.4064)
			(stroke
				(width 0.1524)
				(type default)
			)
			(layer "F.SilkS")
		)
		(fp_line
			(start 0.7874 0.4064)
			(end -0.7874 0.4064)
			(stroke
				(width 0.1524)
				(type default)
			)
			(layer "F.SilkS")
		)
		(fp_line
			(start -0.67945 -0.305054)
			(end -0.12065 -0.305054)
			(stroke
				(width 0.1)
				(type default)
			)
			(layer "F.Fab")
		)
		(fp_line
			(start -0.67945 0.3048)
			(end -0.67945 -0.305054)
			(stroke
				(width 0.1)
				(type default)
			)
			(layer "F.Fab")
		)
		(fp_line
			(start -0.12065 -0.305054)
			(end -0.12065 -0.2794)
			(stroke
				(width 0.1)
				(type default)
			)
			(layer "F.Fab")
		)
		(fp_line
			(start -0.12065 -0.2794)
			(end 0.12065 -0.2794)
			(stroke
				(width 0.1)
				(type default)
			)
			(layer "F.Fab")
		)
		(fp_line
			(start -0.12065 0.2794)
			(end -0.12065 0.3048)
			(stroke
				(width 0.1)
				(type default)
			)
			(layer "F.Fab")
		)
		(fp_line
			(start -0.12065 0.3048)
			(end -0.67945 0.3048)
			(stroke
				(width 0.1)
				(type default)
			)
			(layer "F.Fab")
		)
		(fp_line
			(start 0.120396 0.2794)
			(end -0.12065 0.2794)
			(stroke
				(width 0.1)
				(type default)
			)
			(layer "F.Fab")
		)
		(fp_line
			(start 0.120396 0.3048)
			(end 0.120396 0.2794)
			(stroke
				(width 0.1)
				(type default)
			)
			(layer "F.Fab")
		)
		(fp_line
			(start 0.12065 -0.3048)
			(end 0.67945 -0.3048)
			(stroke
				(width 0.1)
				(type default)
			)
			(layer "F.Fab")
		)
		(fp_line
			(start 0.12065 -0.2794)
			(end 0.12065 -0.3048)
			(stroke
				(width 0.1)
				(type default)
			)
			(layer "F.Fab")
		)
		(fp_line
			(start 0.67945 -0.3048)
			(end 0.67945 0.3048)
			(stroke
				(width 0.1)
				(type default)
			)
			(layer "F.Fab")
		)
		(fp_line
			(start 0.67945 0.3048)
			(end 0.120396 0.3048)
			(stroke
				(width 0.1)
				(type default)
			)
			(layer "F.Fab")
		)
		(pad "1" smd circle
			(at -0.40005 0)
			(size 0 0)
			(layers "F.Cu" "F.Mask" "F.Paste")
			(net "P12V_HPDB_0_TIMER")
		)
		(pad "2" smd circle
			(at 0.40005 0)
			(size 0 0)
			(layers "F.Cu" "F.Mask" "F.Paste")
			(net "GND")
		)
	)
	(footprint ""
		(layer "F.Cu")
		(at 213.36 -95.504 -90)
		(property "Reference" "R55"
			(at 0 0 270)
			(layer "F.SilkS")
			(hide yes)
			(effects
				(font
					(size 1.27 1.27)
				)
			)
		)
		(property "Value" ""
			(at 0 0 270)
			(layer "F.Fab")
			(effects
				(font
					(size 1.27 1.27)
				)
			)
		)
		(duplicate_pad_numbers_are_jumpers no)
		(fp_line
			(start -2.234946 0.9271)
			(end -2.234946 -0.9271)
			(stroke
				(width 0.1524)
				(type default)
			)
			(layer "F.SilkS")
		)
		(fp_line
			(start 2.234946 0.9271)
			(end -2.234946 0.9271)
			(stroke
				(width 0.1524)
				(type default)
			)
			(layer "F.SilkS")
		)
		(fp_line
			(start -2.234946 -0.9271)
			(end 2.234946 -0.9271)
			(stroke
				(width 0.1524)
				(type default)
			)
			(layer "F.SilkS")
		)
		(fp_line
			(start 2.234946 -0.9271)
			(end 2.234946 0.9271)
			(stroke
				(width 0.1524)
				(type default)
			)
			(layer "F.SilkS")
		)
		(fp_line
			(start -1.575054 0.824992)
			(end 1.575054 0.824992)
			(stroke
				(width 0.1)
				(type default)
			)
			(layer "F.Fab")
		)
		(fp_line
			(start 1.575054 0.824992)
			(end 1.575054 -0.824992)
			(stroke
				(width 0.1)
				(type default)
			)
			(layer "F.Fab")
		)
		(fp_line
			(start -1.575054 -0.824992)
			(end -1.575054 0.824992)
			(stroke
				(width 0.1)
				(type default)
			)
			(layer "F.Fab")
		)
		(fp_line
			(start 1.575054 -0.824992)
			(end -1.575054 -0.824992)
			(stroke
				(width 0.1)
				(type default)
			)
			(layer "F.Fab")
		)
		(pad "1" smd rect
			(at -1.599946 0 270)
			(size 1.016 1.6002)
			(layers "F.Cu" "F.Mask" "F.Paste")
			(net "P52V_HS")
		)
		(pad "2" smd rect
			(at 1.599946 0 270)
			(size 1.016 1.6002)
			(layers "F.Cu" "F.Mask" "F.Paste")
			(net "LED_D1_R1")
		)
	)
	(footprint ""
		(layer "F.Cu")
		(at 264.808716 -33.341818 180)
		(property "Reference" "PR211"
			(at 0 0 180)
			(layer "F.SilkS")
			(hide yes)
			(effects
				(font
					(size 1.27 1.27)
				)
			)
		)
		(property "Value" ""
			(at 0 0 180)
			(layer "F.Fab")
			(effects
				(font
					(size 1.27 1.27)
				)
			)
		)
		(duplicate_pad_numbers_are_jumpers no)
		(fp_line
			(start 0.7874 0.4064)
			(end -0.7874 0.4064)
			(stroke
				(width 0.1524)
				(type default)
			)
			(layer "F.SilkS")
		)
		(fp_line
			(start 0.7874 -0.4064)
			(end 0.7874 0.4064)
			(stroke
				(width 0.1524)
				(type default)
			)
			(layer "F.SilkS")
		)
		(fp_line
			(start -0.7874 0.4064)
			(end -0.7874 -0.4064)
			(stroke
				(width 0.1524)
				(type default)
			)
			(layer "F.SilkS")
		)
		(fp_line
			(start -0.7874 -0.4064)
			(end 0.7874 -0.4064)
			(stroke
				(width 0.1524)
				(type default)
			)
			(layer "F.SilkS")
		)
		(fp_line
			(start 0.67945 0.3048)
			(end 0.120396 0.3048)
			(stroke
				(width 0.1)
				(type default)
			)
			(layer "F.Fab")
		)
		(fp_line
			(start 0.67945 -0.3048)
			(end 0.67945 0.3048)
			(stroke
				(width 0.1)
				(type default)
			)
			(layer "F.Fab")
		)
		(fp_line
			(start 0.12065 -0.2794)
			(end 0.12065 -0.3048)
			(stroke
				(width 0.1)
				(type default)
			)
			(layer "F.Fab")
		)
		(fp_line
			(start 0.12065 -0.3048)
			(end 0.67945 -0.3048)
			(stroke
				(width 0.1)
				(type default)
			)
			(layer "F.Fab")
		)
		(fp_line
			(start 0.120396 0.3048)
			(end 0.120396 0.2794)
			(stroke
				(width 0.1)
				(type default)
			)
			(layer "F.Fab")
		)
		(fp_line
			(start 0.120396 0.2794)
			(end -0.12065 0.2794)
			(stroke
				(width 0.1)
				(type default)
			)
			(layer "F.Fab")
		)
		(fp_line
			(start -0.12065 0.3048)
			(end -0.67945 0.3048)
			(stroke
				(width 0.1)
				(type default)
			)
			(layer "F.Fab")
		)
		(fp_line
			(start -0.12065 0.2794)
			(end -0.12065 0.3048)
			(stroke
				(width 0.1)
				(type default)
			)
			(layer "F.Fab")
		)
		(fp_line
			(start -0.12065 -0.2794)
			(end 0.12065 -0.2794)
			(stroke
				(width 0.1)
				(type default)
			)
			(layer "F.Fab")
		)
		(fp_line
			(start -0.12065 -0.305054)
			(end -0.12065 -0.2794)
			(stroke
				(width 0.1)
				(type default)
			)
			(layer "F.Fab")
		)
		(fp_line
			(start -0.67945 0.3048)
			(end -0.67945 -0.305054)
			(stroke
				(width 0.1)
				(type default)
			)
			(layer "F.Fab")
		)
		(fp_line
			(start -0.67945 -0.305054)
			(end -0.12065 -0.305054)
			(stroke
				(width 0.1)
				(type default)
			)
			(layer "F.Fab")
		)
		(pad "1" smd circle
			(at -0.40005 0 180)
			(size 0 0)
			(layers "F.Cu" "F.Mask" "F.Paste")
			(net "HS1_TMR2")
		)
		(pad "2" smd circle
			(at 0.40005 0 180)
			(size 0 0)
			(layers "F.Cu" "F.Mask" "F.Paste")
			(net "GND_FIELD_SIGNAL")
		)
	)
)
